(kicad_pcb
	(version 20260206)
	(generator "pcbnew")
	(generator_version "10.0")
	(general
		(thickness 1.6)
		(legacy_teardrops no)
	)
	(paper "A4")
	(title_block
		(title "01162023_DA0F0TEBIF0_F0T_Expander_BD_F_brd_V02_OCP.brd")
		(comment 1 "Grand Teton / footprints 761-766 of 9728")
	)
	(layers
		(0 "F.Cu" signal "TOP")
		(4 "In1.Cu" signal "GND")
		(6 "In2.Cu" signal "VCC")
		(8 "In3.Cu" signal "VCC1")
		(10 "In4.Cu" signal "GND1")
		(12 "In5.Cu" signal "IN1")
		(14 "In6.Cu" signal "GND2")
		(16 "In7.Cu" signal "IN2")
		(18 "In8.Cu" signal "GND3")
		(20 "In9.Cu" signal "IN3")
		(22 "In10.Cu" signal "GND4")
		(24 "In11.Cu" signal "IN4")
		(26 "In12.Cu" signal "GND5")
		(28 "In13.Cu" signal "IN5")
		(30 "In14.Cu" signal "GND6")
		(32 "In15.Cu" signal "IN6")
		(34 "In16.Cu" signal "GND7")
		(2 "B.Cu" signal "BOTTOM")
		(9 "F.Adhes" user "F.Adhesive")
		(11 "B.Adhes" user "B.Adhesive")
		(13 "F.Paste" user "Package Geometry/Pastemask Top")
		(15 "B.Paste" user "Package Geometry/Pastemask Bottom")
		(5 "F.SilkS" user "Ref Des/Silkscreen Top")
		(7 "B.SilkS" user "Ref Des/Silkscreen Bottom")
		(1 "F.Mask" user "Board Geometry/Soldermask Top")
		(3 "B.Mask" user "Board Geometry/Soldermask Bottom")
		(17 "Dwgs.User" user "User.Drawings")
		(19 "Cmts.User" user "User.Comments")
		(21 "Eco1.User" user "User.Eco1")
		(23 "Eco2.User" user "User.Eco2")
		(25 "Edge.Cuts" user "Board Geometry/Outline")
		(27 "Margin" user)
		(31 "F.CrtYd" user "Package Geometry/Place Bound Top")
		(29 "B.CrtYd" user "Package Geometry/Place Bound Bottom")
		(35 "F.Fab" user "Ref Des/Assembly Top")
		(33 "B.Fab" user "Ref Des/Assembly Bottom")
	)
	(footprint ""
		(layer "F.Cu")
		(at 346.075 -169.291)
		(property "Reference" "U348"
			(at -1.4478 -4.613148 0)
			(unlocked yes)
			(layer "F.SilkS")
			(effects
				(font
					(size 0.7874 0.5842)
					(thickness 0.1524)
				)
				(justify left)
			)
		)
		(property "Value" ""
			(at 0 0 0)
			(layer "F.Fab")
			(effects
				(font
					(size 1.27 1.27)
				)
			)
		)
		(duplicate_pad_numbers_are_jumpers no)
		(fp_line
			(start -2.097532 -3.949954)
			(end -2.097532 3.949954)
			(stroke
				(width 0.1524)
				(type default)
			)
			(layer "F.SilkS")
		)
		(fp_line
			(start -2.097532 3.949954)
			(end 2.097532 3.949954)
			(stroke
				(width 0.1524)
				(type default)
			)
			(layer "F.SilkS")
		)
		(fp_line
			(start -1.409954 -3.949954)
			(end -2.097532 -3.949954)
			(stroke
				(width 0.1524)
				(type default)
			)
			(layer "F.SilkS")
		)
		(fp_line
			(start 0 -2.54)
			(end -1.409954 -3.949954)
			(stroke
				(width 0.1524)
				(type default)
			)
			(layer "F.SilkS")
		)
		(fp_line
			(start 1.409954 -3.949954)
			(end 0 -2.54)
			(stroke
				(width 0.1524)
				(type default)
			)
			(layer "F.SilkS")
		)
		(fp_line
			(start 2.097532 -3.949954)
			(end 1.409954 -3.949954)
			(stroke
				(width 0.1524)
				(type default)
			)
			(layer "F.SilkS")
		)
		(fp_line
			(start 2.097532 3.949954)
			(end 2.097532 -3.949954)
			(stroke
				(width 0.1524)
				(type default)
			)
			(layer "F.SilkS")
		)
		(fp_poly
			(pts
				(xy -4.7498 -4.182872) (xy -4.7498 -3.166872) (xy -3.7338 -3.674872)
			)
			(stroke
				(width 0)
				(type default)
			)
			(fill yes)
			(layer "F.SilkS")
		)
		(fp_line
			(start -2.249932 -3.949954)
			(end -2.249932 3.949954)
			(stroke
				(width 0.1)
				(type default)
			)
			(layer "F.Fab")
		)
		(fp_line
			(start -2.249932 3.949954)
			(end 2.249932 3.949954)
			(stroke
				(width 0.1)
				(type default)
			)
			(layer "F.Fab")
		)
		(fp_line
			(start 2.249932 -3.949954)
			(end -2.249932 -3.949954)
			(stroke
				(width 0.1)
				(type default)
			)
			(layer "F.Fab")
		)
		(fp_line
			(start 2.249932 3.949954)
			(end 2.249932 -3.949954)
			(stroke
				(width 0.1)
				(type default)
			)
			(layer "F.Fab")
		)
		(fp_poly
			(pts
				(xy -4.7498 -4.182872) (xy -4.7498 -3.166872) (xy -3.7338 -3.674872)
			)
			(stroke
				(width 0)
				(type default)
			)
			(fill yes)
			(layer "F.Fab")
		)
		(pad "1" smd rect
			(at -2.925064 -3.674872 270)
			(size 0.6096 1.3716)
			(layers "F.Cu" "F.Mask" "F.Paste")
			(net "PEX2_PCA9555_1_INT_N")
		)
		(pad "2" smd rect
			(at -2.925064 -2.925064 270)
			(size 0.4064 1.3716)
			(layers "F.Cu" "F.Mask" "F.Paste")
			(net "PCA9555_1_PEX2_A1")
		)
		(pad "3" smd rect
			(at -2.925064 -2.275078 270)
			(size 0.4064 1.3716)
			(layers "F.Cu" "F.Mask" "F.Paste")
			(net "PCA9555_1_PEX2_A2")
		)
		(pad "4" smd rect
			(at -2.925064 -1.625092 270)
			(size 0.4064 1.3716)
			(layers "F.Cu" "F.Mask" "F.Paste")
			(net "PRSNT_SSD10_FPGA_PCA9555_N")
		)
		(pad "5" smd rect
			(at -2.925064 -0.975106 270)
			(size 0.4064 1.3716)
			(layers "F.Cu" "F.Mask" "F.Paste")
			(net "SSD10_PEX_PWR_EN")
		)
		(pad "6" smd rect
			(at -2.925064 -0.32512 270)
			(size 0.4064 1.3716)
			(layers "F.Cu" "F.Mask" "F.Paste")
			(net "RST_PEX_SSD10_PERST_N")
		)
		(pad "7" smd rect
			(at -2.925064 0.32512 270)
			(size 0.4064 1.3716)
			(layers "F.Cu" "F.Mask" "F.Paste")
			(net "Net_1178")
		)
		(pad "8" smd rect
			(at -2.925064 0.975106 270)
			(size 0.4064 1.3716)
			(layers "F.Cu" "F.Mask" "F.Paste")
			(net "PRSNT_SSD11_FPGA_PCA9555_N")
		)
		(pad "9" smd rect
			(at -2.925064 1.625092 270)
			(size 0.4064 1.3716)
			(layers "F.Cu" "F.Mask" "F.Paste")
			(net "SSD11_PEX_PWR_EN")
		)
		(pad "10" smd rect
			(at -2.925064 2.275078 270)
			(size 0.4064 1.3716)
			(layers "F.Cu" "F.Mask" "F.Paste")
			(net "RST_PEX_SSD11_PERST_N")
		)
		(pad "11" smd rect
			(at -2.925064 2.925064 270)
			(size 0.4064 1.3716)
			(layers "F.Cu" "F.Mask" "F.Paste")
			(net "Net_1179")
		)
		(pad "12" smd rect
			(at -2.925064 3.674872 270)
			(size 0.6096 1.3716)
			(layers "F.Cu" "F.Mask" "F.Paste")
			(net "GND")
		)
		(pad "13" smd rect
			(at 2.925064 3.674872 270)
			(size 0.6096 1.3716)
			(layers "F.Cu" "F.Mask" "F.Paste")
			(net "PRSNT_NIC5_FPGA_PCA9555_N")
		)
		(pad "14" smd rect
			(at 2.925064 2.925064 270)
			(size 0.4064 1.3716)
			(layers "F.Cu" "F.Mask" "F.Paste")
			(net "NIC5_PEX_PWR_EN")
		)
		(pad "15" smd rect
			(at 2.925064 2.275078 270)
			(size 0.4064 1.3716)
			(layers "F.Cu" "F.Mask" "F.Paste")
			(net "RST_PEX_NIC5_PERST_N")
		)
		(pad "16" smd rect
			(at 2.925064 1.625092 270)
			(size 0.4064 1.3716)
			(layers "F.Cu" "F.Mask" "F.Paste")
			(net "Net_1181")
		)
		(pad "17" smd rect
			(at 2.925064 0.975106 270)
			(size 0.4064 1.3716)
			(layers "F.Cu" "F.Mask" "F.Paste")
			(net "Net_8972")
		)
		(pad "18" smd rect
			(at 2.925064 0.32512 270)
			(size 0.4064 1.3716)
			(layers "F.Cu" "F.Mask" "F.Paste")
			(net "Net_8971")
		)
		(pad "19" smd rect
			(at 2.925064 -0.32512 270)
			(size 0.4064 1.3716)
			(layers "F.Cu" "F.Mask" "F.Paste")
			(net "Net_8970")
		)
		(pad "20" smd rect
			(at 2.925064 -0.975106 270)
			(size 0.4064 1.3716)
			(layers "F.Cu" "F.Mask" "F.Paste")
			(net "Net_8969")
		)
		(pad "21" smd rect
			(at 2.925064 -1.625092 270)
			(size 0.4064 1.3716)
			(layers "F.Cu" "F.Mask" "F.Paste")
			(net "PCA9555_1_PEX2_A0")
		)
		(pad "22" smd rect
			(at 2.925064 -2.275078 270)
			(size 0.4064 1.3716)
			(layers "F.Cu" "F.Mask" "F.Paste")
			(net "SMB_PEX2_PCA9555_SCL")
		)
		(pad "23" smd rect
			(at 2.925064 -2.925064 270)
			(size 0.4064 1.3716)
			(layers "F.Cu" "F.Mask" "F.Paste")
			(net "SMB_PEX2_PCA9555_SDA")
		)
		(pad "24" smd rect
			(at 2.925064 -3.674872 270)
			(size 0.6096 1.3716)
			(layers "F.Cu" "F.Mask" "F.Paste")
			(net "P3V3_AUX")
		)
	)
	(footprint ""
		(layer "F.Cu")
		(at 454.313036 -363.462824 180)
		(property "Reference" "R6694"
			(at 0 0 180)
			(layer "F.SilkS")
			(hide yes)
			(effects
				(font
					(size 1.27 1.27)
				)
			)
		)
		(property "Value" ""
			(at 0 0 180)
			(layer "F.Fab")
			(effects
				(font
					(size 1.27 1.27)
				)
			)
		)
		(duplicate_pad_numbers_are_jumpers no)
		(fp_line
			(start 0.7874 0.4064)
			(end -0.7874 0.4064)
			(stroke
				(width 0.1524)
				(type default)
			)
			(layer "F.SilkS")
		)
		(fp_line
			(start 0.7874 -0.4064)
			(end 0.7874 0.4064)
			(stroke
				(width 0.1524)
				(type default)
			)
			(layer "F.SilkS")
		)
		(fp_line
			(start -0.7874 0.4064)
			(end -0.7874 -0.4064)
			(stroke
				(width 0.1524)
				(type default)
			)
			(layer "F.SilkS")
		)
		(fp_line
			(start -0.7874 -0.4064)
			(end 0.7874 -0.4064)
			(stroke
				(width 0.1524)
				(type default)
			)
			(layer "F.SilkS")
		)
		(fp_line
			(start 0.67945 0.3048)
			(end 0.120396 0.3048)
			(stroke
				(width 0.1)
				(type default)
			)
			(layer "F.Fab")
		)
		(fp_line
			(start 0.67945 -0.3048)
			(end 0.67945 0.3048)
			(stroke
				(width 0.1)
				(type default)
			)
			(layer "F.Fab")
		)
		(fp_line
			(start 0.12065 -0.2794)
			(end 0.12065 -0.3048)
			(stroke
				(width 0.1)
				(type default)
			)
			(layer "F.Fab")
		)
		(fp_line
			(start 0.12065 -0.3048)
			(end 0.67945 -0.3048)
			(stroke
				(width 0.1)
				(type default)
			)
			(layer "F.Fab")
		)
		(fp_line
			(start 0.120396 0.3048)
			(end 0.120396 0.2794)
			(stroke
				(width 0.1)
				(type default)
			)
			(layer "F.Fab")
		)
		(fp_line
			(start 0.120396 0.2794)
			(end -0.12065 0.2794)
			(stroke
				(width 0.1)
				(type default)
			)
			(layer "F.Fab")
		)
		(fp_line
			(start -0.12065 0.3048)
			(end -0.67945 0.3048)
			(stroke
				(width 0.1)
				(type default)
			)
			(layer "F.Fab")
		)
		(fp_line
			(start -0.12065 0.2794)
			(end -0.12065 0.3048)
			(stroke
				(width 0.1)
				(type default)
			)
			(layer "F.Fab")
		)
		(fp_line
			(start -0.12065 -0.2794)
			(end 0.12065 -0.2794)
			(stroke
				(width 0.1)
				(type default)
			)
			(layer "F.Fab")
		)
		(fp_line
			(start -0.12065 -0.305054)
			(end -0.12065 -0.2794)
			(stroke
				(width 0.1)
				(type default)
			)
			(layer "F.Fab")
		)
		(fp_line
			(start -0.67945 0.3048)
			(end -0.67945 -0.305054)
			(stroke
				(width 0.1)
				(type default)
			)
			(layer "F.Fab")
		)
		(fp_line
			(start -0.67945 -0.305054)
			(end -0.12065 -0.305054)
			(stroke
				(width 0.1)
				(type default)
			)
			(layer "F.Fab")
		)
		(pad "1" smd circle
			(at -0.40005 0 180)
			(size 0 0)
			(layers "F.Cu" "F.Mask" "F.Paste")
			(net "GPU_3V3IO_RSVD4_ISO")
		)
		(pad "2" smd circle
			(at 0.40005 0 180)
			(size 0 0)
			(layers "F.Cu" "F.Mask" "F.Paste")
			(net "GPU_3V3IO_RSVD4")
		)
	)
	(footprint ""
		(layer "F.Cu")
		(at 92.436442 -350.098614 90)
		(property "Reference" "C97"
			(at 0 0 90)
			(layer "F.SilkS")
			(hide yes)
			(effects
				(font
					(size 1.27 1.27)
				)
			)
		)
		(property "Value" ""
			(at 0 0 90)
			(layer "F.Fab")
			(effects
				(font
					(size 1.27 1.27)
				)
			)
		)
		(duplicate_pad_numbers_are_jumpers no)
		(fp_line
			(start 0.299974 -0.150114)
			(end 0.299974 0.150114)
			(stroke
				(width 0.1)
				(type default)
			)
			(layer "F.Fab")
		)
		(fp_line
			(start -0.299974 -0.150114)
			(end 0.299974 -0.150114)
			(stroke
				(width 0.1)
				(type default)
			)
			(layer "F.Fab")
		)
		(fp_line
			(start 0.299974 0.150114)
			(end -0.299974 0.150114)
			(stroke
				(width 0.1)
				(type default)
			)
			(layer "F.Fab")
		)
		(fp_line
			(start -0.299974 0.150114)
			(end -0.299974 -0.150114)
			(stroke
				(width 0.1)
				(type default)
			)
			(layer "F.Fab")
		)
		(pad "1" smd rect
			(at -0.2667 0 90)
			(size 0.3048 0.381)
			(layers "F.Cu" "F.Mask" "F.Paste")
			(net "P5E_PEX0_STN5_TX_DP<95>")
		)
		(pad "2" smd rect
			(at 0.2667 0 90)
			(size 0.3048 0.381)
			(layers "F.Cu" "F.Mask" "F.Paste")
			(net "P5E_PEX0_STN5_TX_C_DP<95>")
		)
	)
	(footprint ""
		(layer "F.Cu")
		(at 366.139984 -70.52437 90)
		(property "Reference" "PC883"
			(at 0 0 90)
			(layer "F.SilkS")
			(hide yes)
			(effects
				(font
					(size 1.27 1.27)
				)
			)
		)
		(property "Value" ""
			(at 0 0 90)
			(layer "F.Fab")
			(effects
				(font
					(size 1.27 1.27)
				)
			)
		)
		(duplicate_pad_numbers_are_jumpers no)
		(fp_line
			(start 1.524 -0.762)
			(end 1.524 0.762)
			(stroke
				(width 0.1524)
				(type default)
			)
			(layer "F.SilkS")
		)
		(fp_line
			(start -1.524 -0.762)
			(end 1.524 -0.762)
			(stroke
				(width 0.1524)
				(type default)
			)
			(layer "F.SilkS")
		)
		(fp_line
			(start 1.524 0.762)
			(end -1.524 0.762)
			(stroke
				(width 0.1524)
				(type default)
			)
			(layer "F.SilkS")
		)
		(fp_line
			(start -1.524 0.762)
			(end -1.524 -0.762)
			(stroke
				(width 0.1524)
				(type default)
			)
			(layer "F.SilkS")
		)
		(fp_line
			(start 1.1049 -0.724916)
			(end -1.1049 -0.724916)
			(stroke
				(width 0.1)
				(type default)
			)
			(layer "F.Fab")
		)
		(fp_line
			(start -1.1049 -0.724916)
			(end -1.1049 0.724916)
			(stroke
				(width 0.1)
				(type default)
			)
			(layer "F.Fab")
		)
		(fp_line
			(start 1.1049 0.724916)
			(end 1.1049 -0.724916)
			(stroke
				(width 0.1)
				(type default)
			)
			(layer "F.Fab")
		)
		(fp_line
			(start -1.1049 0.724916)
			(end 1.1049 0.724916)
			(stroke
				(width 0.1)
				(type default)
			)
			(layer "F.Fab")
		)
		(pad "1" smd rect
			(at -0.889 0 270)
			(size 1.016 1.27)
			(layers "F.Cu" "F.Mask" "F.Paste")
			(net "P12V_SSD12_R")
		)
		(pad "2" smd rect
			(at 0.889 0 270)
			(size 1.016 1.27)
			(layers "F.Cu" "F.Mask" "F.Paste")
			(net "GND")
		)
	)
	(footprint ""
		(layer "F.Cu")
		(at 123.768612 -156.288994 -90)
		(property "Reference" "PR6890"
			(at 0 0 270)
			(layer "F.SilkS")
			(hide yes)
			(effects
				(font
					(size 1.27 1.27)
				)
			)
		)
		(property "Value" ""
			(at 0 0 270)
			(layer "F.Fab")
			(effects
				(font
					(size 1.27 1.27)
				)
			)
		)
		(duplicate_pad_numbers_are_jumpers no)
		(fp_line
			(start -0.7874 0.4064)
			(end -0.7874 -0.4064)
			(stroke
				(width 0.1524)
				(type default)
			)
			(layer "F.SilkS")
		)
		(fp_line
			(start 0.7874 0.4064)
			(end -0.7874 0.4064)
			(stroke
				(width 0.1524)
				(type default)
			)
			(layer "F.SilkS")
		)
		(fp_line
			(start -0.7874 -0.4064)
			(end 0.7874 -0.4064)
			(stroke
				(width 0.1524)
				(type default)
			)
			(layer "F.SilkS")
		)
		(fp_line
			(start 0.7874 -0.4064)
			(end 0.7874 0.4064)
			(stroke
				(width 0.1524)
				(type default)
			)
			(layer "F.SilkS")
		)
		(fp_line
			(start -0.67945 0.3048)
			(end -0.67945 -0.305054)
			(stroke
				(width 0.1)
				(type default)
			)
			(layer "F.Fab")
		)
		(fp_line
			(start -0.12065 0.3048)
			(end -0.67945 0.3048)
			(stroke
				(width 0.1)
				(type default)
			)
			(layer "F.Fab")
		)
		(fp_line
			(start 0.120396 0.3048)
			(end 0.120396 0.2794)
			(stroke
				(width 0.1)
				(type default)
			)
			(layer "F.Fab")
		)
		(fp_line
			(start 0.67945 0.3048)
			(end 0.120396 0.3048)
			(stroke
				(width 0.1)
				(type default)
			)
			(layer "F.Fab")
		)
		(fp_line
			(start -0.12065 0.2794)
			(end -0.12065 0.3048)
			(stroke
				(width 0.1)
				(type default)
			)
			(layer "F.Fab")
		)
		(fp_line
			(start 0.120396 0.2794)
			(end -0.12065 0.2794)
			(stroke
				(width 0.1)
				(type default)
			)
			(layer "F.Fab")
		)
		(fp_line
			(start -0.12065 -0.2794)
			(end 0.12065 -0.2794)
			(stroke
				(width 0.1)
				(type default)
			)
			(layer "F.Fab")
		)
		(fp_line
			(start 0.12065 -0.2794)
			(end 0.12065 -0.3048)
			(stroke
				(width 0.1)
				(type default)
			)
			(layer "F.Fab")
		)
		(fp_line
			(start 0.12065 -0.3048)
			(end 0.67945 -0.3048)
			(stroke
				(width 0.1)
				(type default)
			)
			(layer "F.Fab")
		)
		(fp_line
			(start 0.67945 -0.3048)
			(end 0.67945 0.3048)
			(stroke
				(width 0.1)
				(type default)
			)
			(layer "F.Fab")
		)
		(fp_line
			(start -0.67945 -0.305054)
			(end -0.12065 -0.305054)
			(stroke
				(width 0.1)
				(type default)
			)
			(layer "F.Fab")
		)
		(fp_line
			(start -0.12065 -0.305054)
			(end -0.12065 -0.2794)
			(stroke
				(width 0.1)
				(type default)
			)
			(layer "F.Fab")
		)
		(pad "1" smd circle
			(at -0.40005 0 270)
			(size 0 0)
			(layers "F.Cu" "F.Mask" "F.Paste")
			(net "P12V_NIC2_CO_OV_FB")
		)
		(pad "2" smd circle
			(at 0.40005 0 270)
			(size 0 0)
			(layers "F.Cu" "F.Mask" "F.Paste")
			(net "P12V_AUX")
		)
	)
	(footprint ""
		(layer "F.Cu")
		(at 374.567958 -55.083456)
		(property "Reference" "PC409"
			(at 0 0 0)
			(layer "F.SilkS")
			(hide yes)
			(effects
				(font
					(size 1.27 1.27)
				)
			)
		)
		(property "Value" ""
			(at 0 0 0)
			(layer "F.Fab")
			(effects
				(font
					(size 1.27 1.27)
				)
			)
		)
		(duplicate_pad_numbers_are_jumpers no)
		(fp_line
			(start -0.7874 -0.4064)
			(end 0.7874 -0.4064)
			(stroke
				(width 0.1524)
				(type default)
			)
			(layer "F.SilkS")
		)
		(fp_line
			(start -0.7874 0.4064)
			(end -0.7874 -0.4064)
			(stroke
				(width 0.1524)
				(type default)
			)
			(layer "F.SilkS")
		)
		(fp_line
			(start 0.7874 -0.4064)
			(end 0.7874 0.4064)
			(stroke
				(width 0.1524)
				(type default)
			)
			(layer "F.SilkS")
		)
		(fp_line
			(start 0.7874 0.4064)
			(end -0.7874 0.4064)
			(stroke
				(width 0.1524)
				(type default)
			)
			(layer "F.SilkS")
		)
		(fp_line
			(start -0.67945 -0.305054)
			(end -0.12065 -0.305054)
			(stroke
				(width 0.1)
				(type default)
			)
			(layer "F.Fab")
		)
		(fp_line
			(start -0.67945 0.3048)
			(end -0.67945 -0.305054)
			(stroke
				(width 0.1)
				(type default)
			)
			(layer "F.Fab")
		)
		(fp_line
			(start -0.12065 -0.305054)
			(end -0.12065 -0.2794)
			(stroke
				(width 0.1)
				(type default)
			)
			(layer "F.Fab")
		)
		(fp_line
			(start -0.12065 -0.2794)
			(end 0.12065 -0.2794)
			(stroke
				(width 0.1)
				(type default)
			)
			(layer "F.Fab")
		)
		(fp_line
			(start -0.12065 0.2794)
			(end -0.12065 0.3048)
			(stroke
				(width 0.1)
				(type default)
			)
			(layer "F.Fab")
		)
		(fp_line
			(start -0.12065 0.3048)
			(end -0.67945 0.3048)
			(stroke
				(width 0.1)
				(type default)
			)
			(layer "F.Fab")
		)
		(fp_line
			(start 0.120396 0.2794)
			(end -0.12065 0.2794)
			(stroke
				(width 0.1)
				(type default)
			)
			(layer "F.Fab")
		)
		(fp_line
			(start 0.120396 0.3048)
			(end 0.120396 0.2794)
			(stroke
				(width 0.1)
				(type default)
			)
			(layer "F.Fab")
		)
		(fp_line
			(start 0.12065 -0.3048)
			(end 0.67945 -0.3048)
			(stroke
				(width 0.1)
				(type default)
			)
			(layer "F.Fab")
		)
		(fp_line
			(start 0.12065 -0.2794)
			(end 0.12065 -0.3048)
			(stroke
				(width 0.1)
				(type default)
			)
			(layer "F.Fab")
		)
		(fp_line
			(start 0.67945 -0.3048)
			(end 0.67945 0.3048)
			(stroke
				(width 0.1)
				(type default)
			)
			(layer "F.Fab")
		)
		(fp_line
			(start 0.67945 0.3048)
			(end 0.120396 0.3048)
			(stroke
				(width 0.1)
				(type default)
			)
			(layer "F.Fab")
		)
		(pad "1" smd circle
			(at -0.40005 0)
			(size 0 0)
			(layers "F.Cu" "F.Mask" "F.Paste")
			(net "P5V_AUX")
		)
		(pad "2" smd circle
			(at 0.40005 0)
			(size 0 0)
			(layers "F.Cu" "F.Mask" "F.Paste")
			(net "GND")
		)
	)
)
